(kicad_pcb
	(version 20260206)
	(generator "pcbnew")
	(generator_version "10.0")
	(general
		(thickness 1.6)
		(legacy_teardrops no)
	)
	(paper "A4")
	(title_block
		(title "Wiwynn_Tioga_Pass_MB.brd")
		(comment 1 "Tioga Pass / footprints 1715-1718 of 4770")
	)
	(layers
		(0 "F.Cu" signal "TOP")
		(4 "In1.Cu" signal "L2GND")
		(6 "In2.Cu" signal "L3")
		(8 "In3.Cu" signal "L4GND")
		(10 "In4.Cu" signal "L5")
		(12 "In5.Cu" signal "L6GND")
		(14 "In6.Cu" signal "L7VCC")
		(16 "In7.Cu" signal "L8VCC")
		(18 "In8.Cu" signal "L9GND")
		(20 "In9.Cu" signal "L10")
		(22 "In10.Cu" signal "L11GND")
		(24 "In11.Cu" signal "L12")
		(26 "In12.Cu" signal "L13GND")
		(2 "B.Cu" signal "BOTTOM")
		(9 "F.Adhes" user "F.Adhesive")
		(11 "B.Adhes" user "B.Adhesive")
		(13 "F.Paste" user "Package Geometry/Pastemask Top")
		(15 "B.Paste" user "Package Geometry/Pastemask Bottom")
		(5 "F.SilkS" user "Ref Des/Silkscreen Top")
		(7 "B.SilkS" user "Ref Des/Silkscreen Bottom")
		(1 "F.Mask" user "Board Geometry/Soldermask Top")
		(3 "B.Mask" user "Board Geometry/Soldermask Bottom")
		(17 "Dwgs.User" user "User.Drawings")
		(19 "Cmts.User" user "User.Comments")
		(21 "Eco1.User" user "User.Eco1")
		(23 "Eco2.User" user "User.Eco2")
		(25 "Edge.Cuts" user "Board Geometry/Outline")
		(27 "Margin" user)
		(31 "F.CrtYd" user "Package Geometry/Place Bound Top")
		(29 "B.CrtYd" user "Package Geometry/Place Bound Bottom")
		(35 "F.Fab" user "Ref Des/Assembly Top")
		(33 "B.Fab" user "Ref Des/Assembly Bottom")
	)
	(footprint ""
		(layer "F.Cu")
		(at 8.818626 -3.357118 180)
		(property "Reference" "R12W33"
			(at -0.8382 -0.67818 180)
			(unlocked yes)
			(layer "F.SilkS")
			(effects
				(font
					(size 0.4064 0.254)
					(thickness 0.1524)
				)
				(justify left)
			)
		)
		(property "Value" ""
			(at 0 0 180)
			(layer "F.Fab")
			(effects
				(font
					(size 1.27 1.27)
				)
			)
		)
		(duplicate_pad_numbers_are_jumpers no)
		(fp_poly
			(pts
				(xy -0.2794 -0.1016) (xy 0.2794 -0.1016) (xy 0.2794 0.9906) (xy -0.2794 0.9906)
			)
			(stroke
				(width 0)
				(type default)
			)
			(fill no)
			(layer "F.CrtYd")
		)
		(fp_line
			(start 0.2794 0.9906)
			(end 0.2794 -0.1016)
			(stroke
				(width 0.1)
				(type default)
			)
			(layer "F.Fab")
		)
		(fp_line
			(start 0.2794 -0.1016)
			(end -0.2794 -0.1016)
			(stroke
				(width 0.1)
				(type default)
			)
			(layer "F.Fab")
		)
		(fp_line
			(start -0.2794 0.9906)
			(end 0.2794 0.9906)
			(stroke
				(width 0.1)
				(type default)
			)
			(layer "F.Fab")
		)
		(fp_line
			(start -0.2794 -0.1016)
			(end -0.2794 0.9906)
			(stroke
				(width 0.1)
				(type default)
			)
			(layer "F.Fab")
		)
		(pad "1" smd rect
			(at 0 0 180)
			(size 0.508 0.508)
			(layers "F.Cu" "F.Mask" "F.Paste")
			(net "TP_PVDDQ_GHJ_MP2")
		)
		(pad "2" smd rect
			(at 0 0.889 180)
			(size 0.508 0.508)
			(layers "F.Cu" "F.Mask" "F.Paste")
			(net "PWRGD_PVDDQ_GHJ")
		)
		(zone
			(layer "F.Cu")
			(hatch none 0.5)
			(connect_pads
				(clearance 0)
			)
			(min_thickness 0.25)
			(keepout
				(tracks not_allowed)
				(vias allowed)
				(pads allowed)
				(copperpour not_allowed)
				(footprints allowed)
			)
			(placement
				(enabled no)
				(sheetname "")
			)
			(fill
				(thermal_gap 0.5)
				(thermal_bridge_width 0.5)
				(island_removal_mode 0)
			)
			(polygon
				(pts
					(xy 9.072626 -3.992118) (xy 8.564626 -3.992118) (xy 8.564626 -3.611118) (xy 9.072626 -3.611118)
				)
			)
		)
		(zone
			(layer "F.Cu")
			(hatch none 0.5)
			(connect_pads
				(clearance 0)
			)
			(min_thickness 0.25)
			(keepout
				(tracks allowed)
				(vias not_allowed)
				(pads allowed)
				(copperpour not_allowed)
				(footprints allowed)
			)
			(placement
				(enabled no)
				(sheetname "")
			)
			(fill
				(thermal_gap 0.5)
				(thermal_bridge_width 0.5)
				(island_removal_mode 0)
			)
			(polygon
				(pts
					(xy 9.072626 -3.611118) (xy 8.564626 -3.611118) (xy 8.564626 -3.992118) (xy 9.072626 -3.992118)
				)
			)
		)
	)
	(footprint ""
		(layer "F.Cu")
		(at -0.3302 -19.2151 90)
		(property "Reference" "C1F26"
			(at 0 0 90)
			(layer "F.SilkS")
			(hide yes)
			(effects
				(font
					(size 1.27 1.27)
				)
			)
		)
		(property "Value" ""
			(at 0 0 90)
			(layer "F.Fab")
			(effects
				(font
					(size 1.27 1.27)
				)
			)
		)
		(duplicate_pad_numbers_are_jumpers no)
		(fp_poly
			(pts
				(xy 0.3048 -0.1016) (xy 0.3048 0.9906) (xy -0.3048 0.9906) (xy -0.3048 -0.1016)
			)
			(stroke
				(width 0)
				(type default)
			)
			(fill no)
			(layer "F.CrtYd")
		)
		(fp_line
			(start 0.3048 -0.1016)
			(end -0.3048 -0.1016)
			(stroke
				(width 0.1)
				(type default)
			)
			(layer "F.Fab")
		)
		(fp_line
			(start -0.3048 -0.1016)
			(end -0.3048 0.9906)
			(stroke
				(width 0.1)
				(type default)
			)
			(layer "F.Fab")
		)
		(fp_line
			(start 0.3048 0.9906)
			(end 0.3048 -0.1016)
			(stroke
				(width 0.1)
				(type default)
			)
			(layer "F.Fab")
		)
		(fp_line
			(start -0.3048 0.9906)
			(end 0.3048 0.9906)
			(stroke
				(width 0.1)
				(type default)
			)
			(layer "F.Fab")
		)
		(pad "1" smd rect
			(at 0 0 90)
			(size 0.508 0.508)
			(layers "F.Cu" "F.Mask" "F.Paste")
			(net "VR_PVDDQ_GHJ_PH2_BOOT")
		)
		(pad "2" smd rect
			(at 0 0.889 90)
			(size 0.508 0.508)
			(layers "F.Cu" "F.Mask" "F.Paste")
			(net "VR_PVDDQ_GHJ_PH2_PHASE")
		)
		(zone
			(layer "F.Cu")
			(hatch none 0.5)
			(connect_pads
				(clearance 0)
			)
			(min_thickness 0.25)
			(keepout
				(tracks allowed)
				(vias not_allowed)
				(pads allowed)
				(copperpour not_allowed)
				(footprints allowed)
			)
			(placement
				(enabled no)
				(sheetname "")
			)
			(fill
				(thermal_gap 0.5)
				(thermal_bridge_width 0.5)
				(island_removal_mode 0)
			)
			(polygon
				(pts
					(xy -0.0762 -18.9611) (xy -0.0762 -19.4691) (xy 0.3048 -19.4691) (xy 0.3048 -18.9611)
				)
			)
		)
		(zone
			(layer "F.Cu")
			(hatch none 0.5)
			(connect_pads
				(clearance 0)
			)
			(min_thickness 0.25)
			(keepout
				(tracks not_allowed)
				(vias allowed)
				(pads allowed)
				(copperpour not_allowed)
				(footprints allowed)
			)
			(placement
				(enabled no)
				(sheetname "")
			)
			(fill
				(thermal_gap 0.5)
				(thermal_bridge_width 0.5)
				(island_removal_mode 0)
			)
			(polygon
				(pts
					(xy 0.3048 -18.9611) (xy 0.3048 -19.4691) (xy -0.0762 -19.4691) (xy -0.0762 -18.9611)
				)
			)
		)
	)
	(footprint ""
		(layer "F.Cu")
		(at 173.609 -3.683 90)
		(property "Reference" "C4G18"
			(at 0 0 90)
			(layer "F.SilkS")
			(hide yes)
			(effects
				(font
					(size 1.27 1.27)
				)
			)
		)
		(property "Value" ""
			(at 0 0 90)
			(layer "F.Fab")
			(effects
				(font
					(size 1.27 1.27)
				)
			)
		)
		(duplicate_pad_numbers_are_jumpers no)
		(fp_rect
			(start 0.3048 0.9906)
			(end -0.3048 -0.1016)
			(stroke
				(width 0)
				(type default)
			)
			(fill no)
			(layer "F.CrtYd")
		)
		(fp_line
			(start 0.3048 -0.1016)
			(end -0.3048 -0.1016)
			(stroke
				(width 0.1)
				(type default)
			)
			(layer "F.Fab")
		)
		(fp_line
			(start -0.3048 -0.1016)
			(end -0.3048 0.9906)
			(stroke
				(width 0.1)
				(type default)
			)
			(layer "F.Fab")
		)
		(fp_line
			(start 0.3048 0.9906)
			(end 0.3048 -0.1016)
			(stroke
				(width 0.1)
				(type default)
			)
			(layer "F.Fab")
		)
		(fp_line
			(start -0.3048 0.9906)
			(end 0.3048 0.9906)
			(stroke
				(width 0.1)
				(type default)
			)
			(layer "F.Fab")
		)
		(pad "1" smd rect
			(at 0 0 90)
			(size 0.508 0.508)
			(layers "F.Cu" "F.Mask" "F.Paste")
			(net "VR_PVTT_GHJ_BIAS")
		)
		(pad "2" smd rect
			(at 0 0.889 90)
			(size 0.508 0.508)
			(layers "F.Cu" "F.Mask" "F.Paste")
			(net "GND")
		)
		(zone
			(layer "F.Cu")
			(hatch none 0.5)
			(connect_pads
				(clearance 0)
			)
			(min_thickness 0.25)
			(keepout
				(tracks allowed)
				(vias not_allowed)
				(pads allowed)
				(copperpour not_allowed)
				(footprints allowed)
			)
			(placement
				(enabled no)
				(sheetname "")
			)
			(fill
				(thermal_gap 0.5)
				(thermal_bridge_width 0.5)
				(island_removal_mode 0)
			)
			(polygon
				(pts
					(xy 174.244 -3.937) (xy 173.863 -3.937) (xy 173.863 -3.429) (xy 174.244 -3.429)
				)
			)
		)
		(zone
			(layer "F.Cu")
			(hatch none 0.5)
			(connect_pads
				(clearance 0)
			)
			(min_thickness 0.25)
			(keepout
				(tracks not_allowed)
				(vias allowed)
				(pads allowed)
				(copperpour not_allowed)
				(footprints allowed)
			)
			(placement
				(enabled no)
				(sheetname "")
			)
			(fill
				(thermal_gap 0.5)
				(thermal_bridge_width 0.5)
				(island_removal_mode 0)
			)
			(polygon
				(pts
					(xy 174.244 -3.937) (xy 173.863 -3.937) (xy 173.863 -3.429) (xy 174.244 -3.429)
				)
			)
		)
	)
	(footprint ""
		(layer "F.Cu")
		(at 478.1931 -40.4114 -90)
		(property "Reference" "R9E23"
			(at 0 0 270)
			(layer "F.SilkS")
			(hide yes)
			(effects
				(font
					(size 1.27 1.27)
				)
			)
		)
		(property "Value" ""
			(at 0 0 270)
			(layer "F.Fab")
			(effects
				(font
					(size 1.27 1.27)
				)
			)
		)
		(duplicate_pad_numbers_are_jumpers no)
		(fp_poly
			(pts
				(xy -0.2794 -0.1016) (xy 0.2794 -0.1016) (xy 0.2794 0.9906) (xy -0.2794 0.9906)
			)
			(stroke
				(width 0)
				(type default)
			)
			(fill no)
			(layer "F.CrtYd")
		)
		(fp_line
			(start -0.2794 0.9906)
			(end 0.2794 0.9906)
			(stroke
				(width 0.1)
				(type default)
			)
			(layer "F.Fab")
		)
		(fp_line
			(start 0.2794 0.9906)
			(end 0.2794 -0.1016)
			(stroke
				(width 0.1)
				(type default)
			)
			(layer "F.Fab")
		)
		(fp_line
			(start -0.2794 -0.1016)
			(end -0.2794 0.9906)
			(stroke
				(width 0.1)
				(type default)
			)
			(layer "F.Fab")
		)
		(fp_line
			(start 0.2794 -0.1016)
			(end -0.2794 -0.1016)
			(stroke
				(width 0.1)
				(type default)
			)
			(layer "F.Fab")
		)
		(pad "1" smd rect
			(at 0 0 270)
			(size 0.508 0.508)
			(layers "F.Cu" "F.Mask" "F.Paste")
			(net "PD_SPRV_RSET")
		)
		(pad "2" smd rect
			(at 0 0.889 270)
			(size 0.508 0.508)
			(layers "F.Cu" "F.Mask" "F.Paste")
			(net "GND")
		)
		(zone
			(layer "F.Cu")
			(hatch none 0.5)
			(connect_pads
				(clearance 0)
			)
			(min_thickness 0.25)
			(keepout
				(tracks not_allowed)
				(vias allowed)
				(pads allowed)
				(copperpour not_allowed)
				(footprints allowed)
			)
			(placement
				(enabled no)
				(sheetname "")
			)
			(fill
				(thermal_gap 0.5)
				(thermal_bridge_width 0.5)
				(island_removal_mode 0)
			)
			(polygon
				(pts
					(xy 477.5581 -40.6654) (xy 477.5581 -40.1574) (xy 477.9391 -40.1574) (xy 477.9391 -40.6654)
				)
			)
		)
		(zone
			(layer "F.Cu")
			(hatch none 0.5)
			(connect_pads
				(clearance 0)
			)
			(min_thickness 0.25)
			(keepout
				(tracks allowed)
				(vias not_allowed)
				(pads allowed)
				(copperpour not_allowed)
				(footprints allowed)
			)
			(placement
				(enabled no)
				(sheetname "")
			)
			(fill
				(thermal_gap 0.5)
				(thermal_bridge_width 0.5)
				(island_removal_mode 0)
			)
			(polygon
				(pts
					(xy 477.9391 -40.6654) (xy 477.9391 -40.1574) (xy 477.5581 -40.1574) (xy 477.5581 -40.6654)
				)
			)
		)
	)
)
